(kicad_pcb
	(version 20260206)
	(generator "pcbnew")
	(generator_version "10.0")
	(general
		(thickness 1.6)
		(legacy_teardrops no)
	)
	(paper "A4")
	(title_block
		(title "peb — Lightning_PEB_BRD.brd")
		(comment 1 "Lightning (Wiwynn / Facebook NVMe JBOF) / footprints 1957-1963 of 2563")
	)
	(layers
		(0 "F.Cu" signal "TOP")
		(4 "In1.Cu" signal "L2GND")
		(6 "In2.Cu" signal "L3")
		(8 "In3.Cu" signal "L4VCC")
		(10 "In4.Cu" signal "L5VCC")
		(12 "In5.Cu" signal "L6")
		(14 "In6.Cu" signal "L7GND")
		(2 "B.Cu" signal "BOTTOM")
		(9 "F.Adhes" user "F.Adhesive")
		(11 "B.Adhes" user "B.Adhesive")
		(13 "F.Paste" user "Package Geometry/Pastemask Top")
		(15 "B.Paste" user "Package Geometry/Pastemask Bottom")
		(5 "F.SilkS" user "Ref Des/Silkscreen Top")
		(7 "B.SilkS" user "Ref Des/Silkscreen Bottom")
		(1 "F.Mask" user "Board Geometry/Soldermask Top")
		(3 "B.Mask" user "Board Geometry/Soldermask Bottom")
		(17 "Dwgs.User" user "User.Drawings")
		(19 "Cmts.User" user "User.Comments")
		(21 "Eco1.User" user "User.Eco1")
		(23 "Eco2.User" user "User.Eco2")
		(25 "Edge.Cuts" user "Board Geometry/Outline")
		(27 "Margin" user)
		(31 "F.CrtYd" user "Package Geometry/Place Bound Top")
		(29 "B.CrtYd" user "Package Geometry/Place Bound Bottom")
		(35 "F.Fab" user "Ref Des/Assembly Top")
		(33 "B.Fab" user "Ref Des/Assembly Bottom")
	)
	(footprint ""
		(layer "B.Cu")
		(at 231.5972 -60.1218)
		(property "Reference" "C542"
			(at 0 0 0)
			(layer "B.SilkS")
			(hide yes)
			(effects
				(font
					(size 1.27 1.27)
				)
				(justify mirror)
			)
		)
		(property "Value" "SCD1U16V1KX-1-GP"
			(at 2.8321 -1.7399 0)
			(unlocked yes)
			(layer "B.Fab")
			(hide yes)
			(effects
				(font
					(size 1.016 1.016)
					(thickness 0.1524)
				)
				(justify mirror)
			)
		)
		(property "Device Type" "C0201H13"
			(at 2.8321 -3.2639 0)
			(unlocked yes)
			(layer "B.Fab")
			(hide yes)
			(effects
				(font
					(size 1.016 1.016)
					(thickness 0.1524)
				)
				(justify mirror)
			)
		)
		(duplicate_pad_numbers_are_jumpers no)
		(fp_rect
			(start 0.2794 0.6477)
			(end -0.2794 -0.6477)
			(stroke
				(width 0)
				(type default)
			)
			(fill no)
			(layer "B.CrtYd")
		)
		(fp_rect
			(start 0.2794 0.6477)
			(end -0.2794 -0.6477)
			(stroke
				(width 0)
				(type default)
			)
			(fill no)
			(layer "B.Fab")
		)
		(pad "1" smd custom
			(at 0 -0.2794 180)
			(size 0.0762 0.0762)
			(layers "B.Cu" "B.Mask" "B.Paste")
			(net "DUT_AVD_PCIE")
			(options
				(clearance outline)
				(anchor circle)
			)
			(primitives
				(gr_poly
					(pts
						(arc
							(start 0.1524 0.127)
							(mid 0.137521 0.162921)
							(end 0.1016 0.1778)
						)
						(arc
							(start -0.1016 0.1778)
							(mid -0.137521 0.162921)
							(end -0.1524 0.127)
						)
						(arc
							(start -0.1524 -0.127)
							(mid -0.137521 -0.162921)
							(end -0.1016 -0.1778)
						)
						(arc
							(start 0.1016 -0.1778)
							(mid 0.137521 -0.162921)
							(end 0.1524 -0.127)
						)
					)
					(width 0)
					(fill yes)
				)
			)
		)
		(pad "2" smd custom
			(at 0 0.2794 180)
			(size 0.0762 0.0762)
			(layers "B.Cu" "B.Mask" "B.Paste")
			(net "GND")
			(options
				(clearance outline)
				(anchor circle)
			)
			(primitives
				(gr_poly
					(pts
						(arc
							(start 0.1524 0.127)
							(mid 0.137521 0.162921)
							(end 0.1016 0.1778)
						)
						(arc
							(start -0.1016 0.1778)
							(mid -0.137521 0.162921)
							(end -0.1524 0.127)
						)
						(arc
							(start -0.1524 -0.127)
							(mid -0.137521 -0.162921)
							(end -0.1016 -0.1778)
						)
						(arc
							(start 0.1016 -0.1778)
							(mid 0.137521 -0.162921)
							(end 0.1524 -0.127)
						)
					)
					(width 0)
					(fill yes)
				)
			)
		)
	)
	(footprint ""
		(layer "B.Cu")
		(at 36.377118 -126.98984 180)
		(property "Reference" "C212"
			(at 0 0 0)
			(layer "B.SilkS")
			(hide yes)
			(effects
				(font
					(size 1.27 1.27)
				)
				(justify mirror)
			)
		)
		(property "Value" "SC1U10V2KX-4-GP"
			(at -1.1811 -2.7051 180)
			(unlocked yes)
			(layer "B.Fab")
			(hide yes)
			(effects
				(font
					(size 1.016 1.016)
					(thickness 0.1524)
				)
				(justify mirror)
			)
		)
		(property "Device Type" "C402H22"
			(at -1.1811 -4.2291 180)
			(unlocked yes)
			(layer "B.Fab")
			(hide yes)
			(effects
				(font
					(size 1.016 1.016)
					(thickness 0.1524)
				)
				(justify mirror)
			)
		)
		(duplicate_pad_numbers_are_jumpers no)
		(fp_rect
			(start 0.4318 0.9525)
			(end -0.4318 -0.9525)
			(stroke
				(width 0)
				(type default)
			)
			(fill no)
			(layer "B.CrtYd")
		)
		(fp_rect
			(start 0.4318 0.9525)
			(end -0.4318 -0.9525)
			(stroke
				(width 0)
				(type default)
			)
			(fill no)
			(layer "B.Fab")
		)
		(pad "1" smd custom
			(at 0 -0.4445)
			(size 0.1524 0.1524)
			(layers "B.Cu" "B.Mask" "B.Paste")
			(net "P1V26_STBY")
			(options
				(clearance outline)
				(anchor circle)
			)
			(primitives
				(gr_poly
					(pts
						(arc
							(start 0.3048 0.2032)
							(mid 0.275042 0.275042)
							(end 0.2032 0.3048)
						)
						(arc
							(start -0.2032 0.3048)
							(mid -0.275042 0.275042)
							(end -0.3048 0.2032)
						)
						(arc
							(start -0.3048 -0.2032)
							(mid -0.275042 -0.275042)
							(end -0.2032 -0.3048)
						)
						(arc
							(start 0.2032 -0.3048)
							(mid 0.275042 -0.275042)
							(end 0.3048 -0.2032)
						)
					)
					(width 0)
					(fill yes)
				)
			)
		)
		(pad "2" smd custom
			(at 0 0.4445)
			(size 0.1524 0.1524)
			(layers "B.Cu" "B.Mask" "B.Paste")
			(net "GND")
			(options
				(clearance outline)
				(anchor circle)
			)
			(primitives
				(gr_poly
					(pts
						(arc
							(start 0.3048 0.2032)
							(mid 0.275042 0.275042)
							(end 0.2032 0.3048)
						)
						(arc
							(start -0.2032 0.3048)
							(mid -0.275042 0.275042)
							(end -0.3048 0.2032)
						)
						(arc
							(start -0.3048 -0.2032)
							(mid -0.275042 -0.275042)
							(end -0.2032 -0.3048)
						)
						(arc
							(start 0.2032 -0.3048)
							(mid 0.275042 -0.275042)
							(end 0.3048 -0.2032)
						)
					)
					(width 0)
					(fill yes)
				)
			)
		)
	)
	(footprint ""
		(layer "B.Cu")
		(at 30.569154 -159.622744 180)
		(property "Reference" "C199"
			(at 0 0 0)
			(layer "B.SilkS")
			(hide yes)
			(effects
				(font
					(size 1.27 1.27)
				)
				(justify mirror)
			)
		)
		(property "Value" "SC1U10V2KX-4-GP"
			(at -1.1811 -2.7051 180)
			(unlocked yes)
			(layer "B.Fab")
			(hide yes)
			(effects
				(font
					(size 1.016 1.016)
					(thickness 0.1524)
				)
				(justify mirror)
			)
		)
		(property "Device Type" "C402H22"
			(at -1.1811 -4.2291 180)
			(unlocked yes)
			(layer "B.Fab")
			(hide yes)
			(effects
				(font
					(size 1.016 1.016)
					(thickness 0.1524)
				)
				(justify mirror)
			)
		)
		(duplicate_pad_numbers_are_jumpers no)
		(fp_rect
			(start 0.4318 0.9525)
			(end -0.4318 -0.9525)
			(stroke
				(width 0)
				(type default)
			)
			(fill no)
			(layer "B.CrtYd")
		)
		(fp_rect
			(start 0.4318 0.9525)
			(end -0.4318 -0.9525)
			(stroke
				(width 0)
				(type default)
			)
			(fill no)
			(layer "B.Fab")
		)
		(pad "1" smd custom
			(at 0 -0.4445)
			(size 0.1524 0.1524)
			(layers "B.Cu" "B.Mask" "B.Paste")
			(net "P1V53_STBY")
			(options
				(clearance outline)
				(anchor circle)
			)
			(primitives
				(gr_poly
					(pts
						(arc
							(start 0.3048 0.2032)
							(mid 0.275042 0.275042)
							(end 0.2032 0.3048)
						)
						(arc
							(start -0.2032 0.3048)
							(mid -0.275042 0.275042)
							(end -0.3048 0.2032)
						)
						(arc
							(start -0.3048 -0.2032)
							(mid -0.275042 -0.275042)
							(end -0.2032 -0.3048)
						)
						(arc
							(start 0.2032 -0.3048)
							(mid 0.275042 -0.275042)
							(end 0.3048 -0.2032)
						)
					)
					(width 0)
					(fill yes)
				)
			)
		)
		(pad "2" smd custom
			(at 0 0.4445)
			(size 0.1524 0.1524)
			(layers "B.Cu" "B.Mask" "B.Paste")
			(net "GND")
			(options
				(clearance outline)
				(anchor circle)
			)
			(primitives
				(gr_poly
					(pts
						(arc
							(start 0.3048 0.2032)
							(mid 0.275042 0.275042)
							(end 0.2032 0.3048)
						)
						(arc
							(start -0.2032 0.3048)
							(mid -0.275042 0.275042)
							(end -0.3048 0.2032)
						)
						(arc
							(start -0.3048 -0.2032)
							(mid -0.275042 -0.275042)
							(end -0.2032 -0.3048)
						)
						(arc
							(start 0.2032 -0.3048)
							(mid 0.275042 -0.275042)
							(end 0.3048 -0.2032)
						)
					)
					(width 0)
					(fill yes)
				)
			)
		)
	)
	(footprint ""
		(layer "B.Cu")
		(at 27.9654 -185.9026 -90)
		(property "Reference" "R448"
			(at 0 0 90)
			(layer "B.SilkS")
			(hide yes)
			(effects
				(font
					(size 1.27 1.27)
				)
				(justify mirror)
			)
		)
		(property "Value" "0R2J-2-GP"
			(at -0.064008 -3.993896 270)
			(unlocked yes)
			(layer "B.Fab")
			(hide yes)
			(effects
				(font
					(size 1.016 1.016)
					(thickness 0.1524)
				)
				(justify mirror)
			)
		)
		(property "Device Type" "R402H16"
			(at -0.064008 -5.517896 270)
			(unlocked yes)
			(layer "B.Fab")
			(hide yes)
			(effects
				(font
					(size 1.016 1.016)
					(thickness 0.1524)
				)
				(justify mirror)
			)
		)
		(duplicate_pad_numbers_are_jumpers no)
		(fp_line
			(start -0.508 -0.9398)
			(end 0.508 -0.9398)
			(stroke
				(width 0.1524)
				(type default)
			)
			(layer "B.SilkS")
		)
		(fp_line
			(start 0.508 -0.9398)
			(end 0.508 0.9398)
			(stroke
				(width 0.1524)
				(type default)
			)
			(layer "B.SilkS")
		)
		(fp_rect
			(start 0.508 0.9398)
			(end -0.508 -0.9398)
			(stroke
				(width 0)
				(type default)
			)
			(fill no)
			(layer "B.CrtYd")
		)
		(fp_rect
			(start 0.508 0.9398)
			(end -0.508 -0.9398)
			(stroke
				(width 0)
				(type default)
			)
			(fill no)
			(layer "B.Fab")
		)
		(pad "1" smd custom
			(at 0 -0.4445 90)
			(size 0.1397 0.1397)
			(layers "B.Cu" "B.Mask" "B.Paste")
			(net "BMC_I2C5_D_PEB_DEVICE_SCL")
			(options
				(clearance outline)
				(anchor circle)
			)
			(primitives
				(gr_poly
					(pts
						(arc
							(start -0.1778 0.2794)
							(mid -0.249642 0.249642)
							(end -0.2794 0.1778)
						)
						(arc
							(start -0.2794 -0.1778)
							(mid -0.249642 -0.249642)
							(end -0.1778 -0.2794)
						)
						(arc
							(start 0.1778 -0.2794)
							(mid 0.249642 -0.249642)
							(end 0.2794 -0.1778)
						)
						(arc
							(start 0.2794 0.1778)
							(mid 0.249642 0.249642)
							(end 0.1778 0.2794)
						)
					)
					(width 0)
					(fill yes)
				)
			)
		)
		(pad "2" smd custom
			(at 0 0.4445 90)
			(size 0.1397 0.1397)
			(layers "B.Cu" "B.Mask" "B.Paste")
			(net "BMC_I2C5_D_PEB_SCL")
			(options
				(clearance outline)
				(anchor circle)
			)
			(primitives
				(gr_poly
					(pts
						(arc
							(start -0.1778 0.2794)
							(mid -0.249642 0.249642)
							(end -0.2794 0.1778)
						)
						(arc
							(start -0.2794 -0.1778)
							(mid -0.249642 -0.249642)
							(end -0.1778 -0.2794)
						)
						(arc
							(start 0.1778 -0.2794)
							(mid 0.249642 -0.249642)
							(end 0.2794 -0.1778)
						)
						(arc
							(start 0.2794 0.1778)
							(mid 0.249642 0.249642)
							(end 0.1778 0.2794)
						)
					)
					(width 0)
					(fill yes)
				)
			)
		)
	)
	(footprint ""
		(layer "B.Cu")
		(at 20.955 -134.747 -90)
		(property "Reference" "R523"
			(at 0 0 90)
			(layer "B.SilkS")
			(hide yes)
			(effects
				(font
					(size 1.27 1.27)
				)
				(justify mirror)
			)
		)
		(property "Value" "0R2J-2-GP"
			(at -0.064008 -3.993896 270)
			(unlocked yes)
			(layer "B.Fab")
			(hide yes)
			(effects
				(font
					(size 1.016 1.016)
					(thickness 0.1524)
				)
				(justify mirror)
			)
		)
		(property "Device Type" "R402H16"
			(at -0.064008 -5.517896 270)
			(unlocked yes)
			(layer "B.Fab")
			(hide yes)
			(effects
				(font
					(size 1.016 1.016)
					(thickness 0.1524)
				)
				(justify mirror)
			)
		)
		(duplicate_pad_numbers_are_jumpers no)
		(fp_line
			(start -0.508 -0.9398)
			(end 0.508 -0.9398)
			(stroke
				(width 0.1524)
				(type default)
			)
			(layer "B.SilkS")
		)
		(fp_line
			(start 0.508 -0.9398)
			(end 0.508 0.9398)
			(stroke
				(width 0.1524)
				(type default)
			)
			(layer "B.SilkS")
		)
		(fp_rect
			(start 0.508 0.9398)
			(end -0.508 -0.9398)
			(stroke
				(width 0)
				(type default)
			)
			(fill no)
			(layer "B.CrtYd")
		)
		(fp_rect
			(start 0.508 0.9398)
			(end -0.508 -0.9398)
			(stroke
				(width 0)
				(type default)
			)
			(fill no)
			(layer "B.Fab")
		)
		(pad "1" smd custom
			(at 0 -0.4445 90)
			(size 0.1397 0.1397)
			(layers "B.Cu" "B.Mask" "B.Paste")
			(net "EXP_TRAY_ID_BMC")
			(options
				(clearance outline)
				(anchor circle)
			)
			(primitives
				(gr_poly
					(pts
						(arc
							(start -0.1778 0.2794)
							(mid -0.249642 0.249642)
							(end -0.2794 0.1778)
						)
						(arc
							(start -0.2794 -0.1778)
							(mid -0.249642 -0.249642)
							(end -0.1778 -0.2794)
						)
						(arc
							(start 0.1778 -0.2794)
							(mid 0.249642 -0.249642)
							(end 0.2794 -0.1778)
						)
						(arc
							(start 0.2794 0.1778)
							(mid 0.249642 0.249642)
							(end 0.1778 0.2794)
						)
					)
					(width 0)
					(fill yes)
				)
			)
		)
		(pad "2" smd custom
			(at 0 0.4445 90)
			(size 0.1397 0.1397)
			(layers "B.Cu" "B.Mask" "B.Paste")
			(net "EXP_TRAY_ID")
			(options
				(clearance outline)
				(anchor circle)
			)
			(primitives
				(gr_poly
					(pts
						(arc
							(start -0.1778 0.2794)
							(mid -0.249642 0.249642)
							(end -0.2794 0.1778)
						)
						(arc
							(start -0.2794 -0.1778)
							(mid -0.249642 -0.249642)
							(end -0.1778 -0.2794)
						)
						(arc
							(start 0.1778 -0.2794)
							(mid 0.249642 -0.249642)
							(end 0.2794 -0.1778)
						)
						(arc
							(start 0.2794 0.1778)
							(mid 0.249642 0.249642)
							(end 0.1778 0.2794)
						)
					)
					(width 0)
					(fill yes)
				)
			)
		)
	)
	(footprint ""
		(layer "B.Cu")
		(at 240.3856 -40.7162 180)
		(property "Reference" "C485"
			(at 0 0 0)
			(layer "B.SilkS")
			(hide yes)
			(effects
				(font
					(size 1.27 1.27)
				)
				(justify mirror)
			)
		)
		(property "Value" "SCD1U16V1KX-1-GP"
			(at 2.8321 -1.7399 180)
			(unlocked yes)
			(layer "B.Fab")
			(hide yes)
			(effects
				(font
					(size 1.016 1.016)
					(thickness 0.1524)
				)
				(justify mirror)
			)
		)
		(property "Device Type" "C0201H13"
			(at 2.8321 -3.2639 180)
			(unlocked yes)
			(layer "B.Fab")
			(hide yes)
			(effects
				(font
					(size 1.016 1.016)
					(thickness 0.1524)
				)
				(justify mirror)
			)
		)
		(duplicate_pad_numbers_are_jumpers no)
		(fp_rect
			(start 0.2794 0.6477)
			(end -0.2794 -0.6477)
			(stroke
				(width 0)
				(type default)
			)
			(fill no)
			(layer "B.CrtYd")
		)
		(fp_rect
			(start 0.2794 0.6477)
			(end -0.2794 -0.6477)
			(stroke
				(width 0)
				(type default)
			)
			(fill no)
			(layer "B.Fab")
		)
		(pad "1" smd custom
			(at 0 -0.2794)
			(size 0.0762 0.0762)
			(layers "B.Cu" "B.Mask" "B.Paste")
			(net "DUT_VDDO_REF")
			(options
				(clearance outline)
				(anchor circle)
			)
			(primitives
				(gr_poly
					(pts
						(arc
							(start 0.1524 0.127)
							(mid 0.137521 0.162921)
							(end 0.1016 0.1778)
						)
						(arc
							(start -0.1016 0.1778)
							(mid -0.137521 0.162921)
							(end -0.1524 0.127)
						)
						(arc
							(start -0.1524 -0.127)
							(mid -0.137521 -0.162921)
							(end -0.1016 -0.1778)
						)
						(arc
							(start 0.1016 -0.1778)
							(mid 0.137521 -0.162921)
							(end 0.1524 -0.127)
						)
					)
					(width 0)
					(fill yes)
				)
			)
		)
		(pad "2" smd custom
			(at 0 0.2794)
			(size 0.0762 0.0762)
			(layers "B.Cu" "B.Mask" "B.Paste")
			(net "GND")
			(options
				(clearance outline)
				(anchor circle)
			)
			(primitives
				(gr_poly
					(pts
						(arc
							(start 0.1524 0.127)
							(mid 0.137521 0.162921)
							(end 0.1016 0.1778)
						)
						(arc
							(start -0.1016 0.1778)
							(mid -0.137521 0.162921)
							(end -0.1524 0.127)
						)
						(arc
							(start -0.1524 -0.127)
							(mid -0.137521 -0.162921)
							(end -0.1016 -0.1778)
						)
						(arc
							(start 0.1016 -0.1778)
							(mid 0.137521 -0.162921)
							(end 0.1524 -0.127)
						)
					)
					(width 0)
					(fill yes)
				)
			)
		)
	)
	(footprint ""
		(layer "B.Cu")
		(at 232.605072 -45.457872)
		(property "Reference" "C546"
			(at 0 0 0)
			(layer "B.SilkS")
			(hide yes)
			(effects
				(font
					(size 1.27 1.27)
				)
				(justify mirror)
			)
		)
		(property "Value" "SCD1U16V1KX-1-GP"
			(at 2.8321 -1.7399 0)
			(unlocked yes)
			(layer "B.Fab")
			(hide yes)
			(effects
				(font
					(size 1.016 1.016)
					(thickness 0.1524)
				)
				(justify mirror)
			)
		)
		(property "Device Type" "C0201H13"
			(at 2.8321 -3.2639 0)
			(unlocked yes)
			(layer "B.Fab")
			(hide yes)
			(effects
				(font
					(size 1.016 1.016)
					(thickness 0.1524)
				)
				(justify mirror)
			)
		)
		(duplicate_pad_numbers_are_jumpers no)
		(fp_rect
			(start 0.2794 0.6477)
			(end -0.2794 -0.6477)
			(stroke
				(width 0)
				(type default)
			)
			(fill no)
			(layer "B.CrtYd")
		)
		(fp_rect
			(start 0.2794 0.6477)
			(end -0.2794 -0.6477)
			(stroke
				(width 0)
				(type default)
			)
			(fill no)
			(layer "B.Fab")
		)
		(pad "1" smd custom
			(at 0 -0.2794 180)
			(size 0.0762 0.0762)
			(layers "B.Cu" "B.Mask" "B.Paste")
			(net "DUT_AVD_PCIE")
			(options
				(clearance outline)
				(anchor circle)
			)
			(primitives
				(gr_poly
					(pts
						(arc
							(start 0.1524 0.127)
							(mid 0.137521 0.162921)
							(end 0.1016 0.1778)
						)
						(arc
							(start -0.1016 0.1778)
							(mid -0.137521 0.162921)
							(end -0.1524 0.127)
						)
						(arc
							(start -0.1524 -0.127)
							(mid -0.137521 -0.162921)
							(end -0.1016 -0.1778)
						)
						(arc
							(start 0.1016 -0.1778)
							(mid 0.137521 -0.162921)
							(end 0.1524 -0.127)
						)
					)
					(width 0)
					(fill yes)
				)
			)
		)
		(pad "2" smd custom
			(at 0 0.2794 180)
			(size 0.0762 0.0762)
			(layers "B.Cu" "B.Mask" "B.Paste")
			(net "GND")
			(options
				(clearance outline)
				(anchor circle)
			)
			(primitives
				(gr_poly
					(pts
						(arc
							(start 0.1524 0.127)
							(mid 0.137521 0.162921)
							(end 0.1016 0.1778)
						)
						(arc
							(start -0.1016 0.1778)
							(mid -0.137521 0.162921)
							(end -0.1524 0.127)
						)
						(arc
							(start -0.1524 -0.127)
							(mid -0.137521 -0.162921)
							(end -0.1016 -0.1778)
						)
						(arc
							(start 0.1016 -0.1778)
							(mid 0.137521 -0.162921)
							(end 0.1524 -0.127)
						)
					)
					(width 0)
					(fill yes)
				)
			)
		)
	)
)
